(kicad_pcb
	(version 20260206)
	(generator "pcbnew")
	(generator_version "10.0")
	(general
		(thickness 1.6)
		(legacy_teardrops no)
	)
	(paper "A4")
	(title_block
		(title "dpb — 14545-sa.0730WZS0815.brd")
		(comment 1 "Honey Badger (Wiwynn) / footprints 10-17 of 1066")
	)
	(layers
		(0 "F.Cu" signal "TOP")
		(4 "In1.Cu" signal "L2GND")
		(6 "In2.Cu" signal "L3")
		(8 "In3.Cu" signal "L4VCC")
		(10 "In4.Cu" signal "L5VCC")
		(12 "In5.Cu" signal "L6")
		(14 "In6.Cu" signal "L7GND")
		(2 "B.Cu" signal "BOTTOM")
		(9 "F.Adhes" user "F.Adhesive")
		(11 "B.Adhes" user "B.Adhesive")
		(13 "F.Paste" user "Package Geometry/Pastemask Top")
		(15 "B.Paste" user "Package Geometry/Pastemask Bottom")
		(5 "F.SilkS" user "Ref Des/Silkscreen Top")
		(7 "B.SilkS" user "Ref Des/Silkscreen Bottom")
		(1 "F.Mask" user "Board Geometry/Soldermask Top")
		(3 "B.Mask" user "Board Geometry/Soldermask Bottom")
		(17 "Dwgs.User" user "User.Drawings")
		(19 "Cmts.User" user "User.Comments")
		(21 "Eco1.User" user "User.Eco1")
		(23 "Eco2.User" user "User.Eco2")
		(25 "Edge.Cuts" user "Board Geometry/Outline")
		(27 "Margin" user)
		(31 "F.CrtYd" user "Package Geometry/Place Bound Top")
		(29 "B.CrtYd" user "Package Geometry/Place Bound Bottom")
		(35 "F.Fab" user "Ref Des/Assembly Top")
		(33 "B.Fab" user "Ref Des/Assembly Bottom")
	)
	(footprint ""
		(layer "F.Cu")
		(at 19.684746 -163.2077 90)
		(property "Reference" "R503"
			(at 0 0 90)
			(layer "F.SilkS")
			(hide yes)
			(effects
				(font
					(size 1.27 1.27)
				)
			)
		)
		(property "Value" "1KR2F-3-GP"
			(at 0.064008 -3.993896 90)
			(unlocked yes)
			(layer "F.Fab")
			(hide yes)
			(effects
				(font
					(size 1.016 1.016)
					(thickness 0.1524)
				)
			)
		)
		(property "Device Type" "R402H16"
			(at 0.064008 -5.517896 90)
			(unlocked yes)
			(layer "F.Fab")
			(hide yes)
			(effects
				(font
					(size 1.016 1.016)
					(thickness 0.1524)
				)
			)
		)
		(duplicate_pad_numbers_are_jumpers no)
		(fp_line
			(start 0.508 -0.9398)
			(end -0.508 -0.9398)
			(stroke
				(width 0.1524)
				(type default)
			)
			(layer "F.SilkS")
		)
		(fp_line
			(start -0.508 -0.9398)
			(end -0.508 0.9398)
			(stroke
				(width 0.1524)
				(type default)
			)
			(layer "F.SilkS")
		)
		(fp_rect
			(start -0.508 0.9398)
			(end 0.508 -0.9398)
			(stroke
				(width 0)
				(type default)
			)
			(fill no)
			(layer "F.CrtYd")
		)
		(fp_rect
			(start -0.508 0.9398)
			(end 0.508 -0.9398)
			(stroke
				(width 0)
				(type default)
			)
			(fill no)
			(layer "F.Fab")
		)
		(pad "1" smd custom
			(at 0 -0.4445 90)
			(size 0.1397 0.1397)
			(layers "F.Cu" "F.Mask" "F.Paste")
			(net "FLT_HDD13_B")
			(options
				(clearance outline)
				(anchor circle)
			)
			(primitives
				(gr_poly
					(pts
						(arc
							(start -0.1778 -0.2794)
							(mid -0.249642 -0.249642)
							(end -0.2794 -0.1778)
						)
						(arc
							(start -0.2794 0.1778)
							(mid -0.249642 0.249642)
							(end -0.1778 0.2794)
						)
						(arc
							(start 0.1778 0.2794)
							(mid 0.249642 0.249642)
							(end 0.2794 0.1778)
						)
						(arc
							(start 0.2794 -0.1778)
							(mid 0.249642 -0.249642)
							(end 0.1778 -0.2794)
						)
					)
					(width 0)
					(fill yes)
				)
			)
		)
		(pad "2" smd custom
			(at 0 0.4445 90)
			(size 0.1397 0.1397)
			(layers "F.Cu" "F.Mask" "F.Paste")
			(net "FLT_HDD13_DRIVE")
			(options
				(clearance outline)
				(anchor circle)
			)
			(primitives
				(gr_poly
					(pts
						(arc
							(start -0.1778 -0.2794)
							(mid -0.249642 -0.249642)
							(end -0.2794 -0.1778)
						)
						(arc
							(start -0.2794 0.1778)
							(mid -0.249642 0.249642)
							(end -0.1778 0.2794)
						)
						(arc
							(start 0.1778 0.2794)
							(mid 0.249642 0.249642)
							(end 0.2794 0.1778)
						)
						(arc
							(start 0.2794 -0.1778)
							(mid 0.249642 -0.249642)
							(end 0.1778 -0.2794)
						)
					)
					(width 0)
					(fill yes)
				)
			)
		)
	)
	(footprint ""
		(layer "F.Cu")
		(at 54.253892 -88.420956 180)
		(property "Reference" "C259"
			(at 0 0 180)
			(layer "F.SilkS")
			(hide yes)
			(effects
				(font
					(size 1.27 1.27)
				)
			)
		)
		(property "Value" "SC1U25V3KX-1-GP"
			(at 0 -2.8194 180)
			(unlocked yes)
			(layer "F.Fab")
			(hide yes)
			(effects
				(font
					(size 1.016 1.016)
					(thickness 0.1524)
				)
			)
		)
		(property "Device Type" "C603H36"
			(at 0 -4.3434 180)
			(unlocked yes)
			(layer "F.Fab")
			(hide yes)
			(effects
				(font
					(size 1.016 1.016)
					(thickness 0.1524)
				)
			)
		)
		(duplicate_pad_numbers_are_jumpers no)
		(fp_line
			(start 0.508 0)
			(end -0.508 0)
			(stroke
				(width 0.2032)
				(type default)
			)
			(layer "F.SilkS")
		)
		(fp_rect
			(start -0.5842 1.3335)
			(end 0.5842 -1.3335)
			(stroke
				(width 0)
				(type default)
			)
			(fill no)
			(layer "F.CrtYd")
		)
		(fp_rect
			(start -0.5842 1.3335)
			(end 0.5842 -1.3335)
			(stroke
				(width 0)
				(type default)
			)
			(fill no)
			(layer "F.Fab")
		)
		(pad "1" smd custom
			(at 0 -0.762 180)
			(size 0.2159 0.2159)
			(layers "F.Cu" "F.Mask" "F.Paste")
			(net "P12V_HDD9")
			(options
				(clearance outline)
				(anchor circle)
			)
			(primitives
				(gr_poly
					(pts
						(arc
							(start -0.3302 -0.4318)
							(mid -0.402042 -0.402042)
							(end -0.4318 -0.3302)
						)
						(arc
							(start -0.4318 0.3302)
							(mid -0.402042 0.402042)
							(end -0.3302 0.4318)
						)
						(arc
							(start 0.3302 0.4318)
							(mid 0.402042 0.402042)
							(end 0.4318 0.3302)
						)
						(arc
							(start 0.4318 -0.3302)
							(mid 0.402042 -0.402042)
							(end 0.3302 -0.4318)
						)
					)
					(width 0)
					(fill yes)
				)
			)
		)
		(pad "2" smd custom
			(at 0 0.762 180)
			(size 0.2159 0.2159)
			(layers "F.Cu" "F.Mask" "F.Paste")
			(net "GND")
			(options
				(clearance outline)
				(anchor circle)
			)
			(primitives
				(gr_poly
					(pts
						(arc
							(start -0.3302 -0.4318)
							(mid -0.402042 -0.402042)
							(end -0.4318 -0.3302)
						)
						(arc
							(start -0.4318 0.3302)
							(mid -0.402042 0.402042)
							(end -0.3302 0.4318)
						)
						(arc
							(start 0.3302 0.4318)
							(mid 0.402042 0.402042)
							(end 0.4318 0.3302)
						)
						(arc
							(start 0.4318 -0.3302)
							(mid 0.402042 -0.402042)
							(end 0.3302 -0.4318)
						)
					)
					(width 0)
					(fill yes)
				)
			)
		)
	)
	(footprint ""
		(layer "F.Cu")
		(at 77.978 -196.342 180)
		(property "Reference" "C387"
			(at 0 0 180)
			(layer "F.SilkS")
			(hide yes)
			(effects
				(font
					(size 1.27 1.27)
				)
			)
		)
		(property "Value" "SCD033U25V2KX-GP"
			(at 1.1811 -2.7051 180)
			(unlocked yes)
			(layer "F.Fab")
			(hide yes)
			(effects
				(font
					(size 1.016 1.016)
					(thickness 0.1524)
				)
			)
		)
		(property "Device Type" "C402H22"
			(at 1.1811 -4.2291 180)
			(unlocked yes)
			(layer "F.Fab")
			(hide yes)
			(effects
				(font
					(size 1.016 1.016)
					(thickness 0.1524)
				)
			)
		)
		(duplicate_pad_numbers_are_jumpers no)
		(fp_rect
			(start -0.4318 0.9525)
			(end 0.4318 -0.9525)
			(stroke
				(width 0)
				(type default)
			)
			(fill no)
			(layer "F.CrtYd")
		)
		(fp_rect
			(start -0.4318 0.9525)
			(end 0.4318 -0.9525)
			(stroke
				(width 0)
				(type default)
			)
			(fill no)
			(layer "F.Fab")
		)
		(pad "1" smd custom
			(at 0 -0.4445 180)
			(size 0.1524 0.1524)
			(layers "F.Cu" "F.Mask" "F.Paste")
			(net "P12V")
			(options
				(clearance outline)
				(anchor circle)
			)
			(primitives
				(gr_poly
					(pts
						(arc
							(start 0.3048 -0.2032)
							(mid 0.275042 -0.275042)
							(end 0.2032 -0.3048)
						)
						(arc
							(start -0.2032 -0.3048)
							(mid -0.275042 -0.275042)
							(end -0.3048 -0.2032)
						)
						(arc
							(start -0.3048 0.2032)
							(mid -0.275042 0.275042)
							(end -0.2032 0.3048)
						)
						(arc
							(start 0.2032 0.3048)
							(mid 0.275042 0.275042)
							(end 0.3048 0.2032)
						)
					)
					(width 0)
					(fill yes)
				)
			)
		)
		(pad "2" smd custom
			(at 0 0.4445 180)
			(size 0.1524 0.1524)
			(layers "F.Cu" "F.Mask" "F.Paste")
			(net "SW_HDD8_N")
			(options
				(clearance outline)
				(anchor circle)
			)
			(primitives
				(gr_poly
					(pts
						(arc
							(start 0.3048 -0.2032)
							(mid 0.275042 -0.275042)
							(end 0.2032 -0.3048)
						)
						(arc
							(start -0.2032 -0.3048)
							(mid -0.275042 -0.275042)
							(end -0.3048 -0.2032)
						)
						(arc
							(start -0.3048 0.2032)
							(mid -0.275042 0.275042)
							(end -0.2032 0.3048)
						)
						(arc
							(start 0.2032 0.3048)
							(mid 0.275042 0.275042)
							(end 0.3048 0.2032)
						)
					)
					(width 0)
					(fill yes)
				)
			)
		)
	)
	(footprint ""
		(layer "F.Cu")
		(at 32.12592 -279.014428 -90)
		(property "Reference" "R450"
			(at 0 0 270)
			(layer "F.SilkS")
			(hide yes)
			(effects
				(font
					(size 1.27 1.27)
				)
			)
		)
		(property "Value" "4K7R2J-2-GP"
			(at 0.064008 -3.993896 270)
			(unlocked yes)
			(layer "F.Fab")
			(hide yes)
			(effects
				(font
					(size 1.016 1.016)
					(thickness 0.1524)
				)
			)
		)
		(property "Device Type" "R402H16"
			(at 0.064008 -5.517896 270)
			(unlocked yes)
			(layer "F.Fab")
			(hide yes)
			(effects
				(font
					(size 1.016 1.016)
					(thickness 0.1524)
				)
			)
		)
		(duplicate_pad_numbers_are_jumpers no)
		(fp_line
			(start -0.508 -0.9398)
			(end -0.508 0.9398)
			(stroke
				(width 0.1524)
				(type default)
			)
			(layer "F.SilkS")
		)
		(fp_line
			(start 0.508 -0.9398)
			(end -0.508 -0.9398)
			(stroke
				(width 0.1524)
				(type default)
			)
			(layer "F.SilkS")
		)
		(fp_rect
			(start -0.508 0.9398)
			(end 0.508 -0.9398)
			(stroke
				(width 0)
				(type default)
			)
			(fill no)
			(layer "F.CrtYd")
		)
		(fp_rect
			(start -0.508 0.9398)
			(end 0.508 -0.9398)
			(stroke
				(width 0)
				(type default)
			)
			(fill no)
			(layer "F.Fab")
		)
		(pad "1" smd custom
			(at 0 -0.4445 270)
			(size 0.1397 0.1397)
			(layers "F.Cu" "F.Mask" "F.Paste")
			(net "P3V3")
			(options
				(clearance outline)
				(anchor circle)
			)
			(primitives
				(gr_poly
					(pts
						(arc
							(start -0.1778 -0.2794)
							(mid -0.249642 -0.249642)
							(end -0.2794 -0.1778)
						)
						(arc
							(start -0.2794 0.1778)
							(mid -0.249642 0.249642)
							(end -0.1778 0.2794)
						)
						(arc
							(start 0.1778 0.2794)
							(mid 0.249642 0.249642)
							(end 0.2794 0.1778)
						)
						(arc
							(start 0.2794 -0.1778)
							(mid 0.249642 -0.249642)
							(end 0.1778 -0.2794)
						)
					)
					(width 0)
					(fill yes)
				)
			)
		)
		(pad "2" smd custom
			(at 0 0.4445 270)
			(size 0.1397 0.1397)
			(layers "F.Cu" "F.Mask" "F.Paste")
			(net "SAS_EXP_A_PWR7")
			(options
				(clearance outline)
				(anchor circle)
			)
			(primitives
				(gr_poly
					(pts
						(arc
							(start -0.1778 -0.2794)
							(mid -0.249642 -0.249642)
							(end -0.2794 -0.1778)
						)
						(arc
							(start -0.2794 0.1778)
							(mid -0.249642 0.249642)
							(end -0.1778 0.2794)
						)
						(arc
							(start 0.1778 0.2794)
							(mid 0.249642 0.249642)
							(end 0.2794 0.1778)
						)
						(arc
							(start 0.2794 -0.1778)
							(mid 0.249642 -0.249642)
							(end 0.1778 -0.2794)
						)
					)
					(width 0)
					(fill yes)
				)
			)
		)
	)
	(footprint ""
		(layer "F.Cu")
		(at 207.137 -483.235)
		(property "Reference" "C364"
			(at 0 0 0)
			(layer "F.SilkS")
			(hide yes)
			(effects
				(font
					(size 1.27 1.27)
				)
			)
		)
		(property "Value" "SCD033U25V2KX-GP"
			(at 1.1811 -2.7051 0)
			(unlocked yes)
			(layer "F.Fab")
			(hide yes)
			(effects
				(font
					(size 1.016 1.016)
					(thickness 0.1524)
				)
			)
		)
		(property "Device Type" "C402H22"
			(at 1.1811 -4.2291 0)
			(unlocked yes)
			(layer "F.Fab")
			(hide yes)
			(effects
				(font
					(size 1.016 1.016)
					(thickness 0.1524)
				)
			)
		)
		(duplicate_pad_numbers_are_jumpers no)
		(fp_rect
			(start -0.4318 0.9525)
			(end 0.4318 -0.9525)
			(stroke
				(width 0)
				(type default)
			)
			(fill no)
			(layer "F.CrtYd")
		)
		(fp_rect
			(start -0.4318 0.9525)
			(end 0.4318 -0.9525)
			(stroke
				(width 0)
				(type default)
			)
			(fill no)
			(layer "F.Fab")
		)
		(pad "1" smd custom
			(at 0 -0.4445)
			(size 0.1524 0.1524)
			(layers "F.Cu" "F.Mask" "F.Paste")
			(net "SW_HDD0_P")
			(options
				(clearance outline)
				(anchor circle)
			)
			(primitives
				(gr_poly
					(pts
						(arc
							(start 0.3048 -0.2032)
							(mid 0.275042 -0.275042)
							(end 0.2032 -0.3048)
						)
						(arc
							(start -0.2032 -0.3048)
							(mid -0.275042 -0.275042)
							(end -0.3048 -0.2032)
						)
						(arc
							(start -0.3048 0.2032)
							(mid -0.275042 0.275042)
							(end -0.2032 0.3048)
						)
						(arc
							(start 0.2032 0.3048)
							(mid 0.275042 0.275042)
							(end 0.3048 0.2032)
						)
					)
					(width 0)
					(fill yes)
				)
			)
		)
		(pad "2" smd custom
			(at 0 0.4445)
			(size 0.1524 0.1524)
			(layers "F.Cu" "F.Mask" "F.Paste")
			(net "GND")
			(options
				(clearance outline)
				(anchor circle)
			)
			(primitives
				(gr_poly
					(pts
						(arc
							(start 0.3048 -0.2032)
							(mid 0.275042 -0.275042)
							(end 0.2032 -0.3048)
						)
						(arc
							(start -0.2032 -0.3048)
							(mid -0.275042 -0.275042)
							(end -0.3048 -0.2032)
						)
						(arc
							(start -0.3048 0.2032)
							(mid -0.275042 0.275042)
							(end -0.2032 0.3048)
						)
						(arc
							(start 0.2032 0.3048)
							(mid 0.275042 0.275042)
							(end 0.3048 0.2032)
						)
					)
					(width 0)
					(fill yes)
				)
			)
		)
	)
	(footprint ""
		(layer "F.Cu")
		(at 18.940272 -500.446548 180)
		(property "Reference" "PC31"
			(at 0 0 180)
			(layer "F.SilkS")
			(hide yes)
			(effects
				(font
					(size 1.27 1.27)
				)
			)
		)
		(property "Value" "SC22U25V5MX-GP"
			(at -0.0762 -6.1214 180)
			(unlocked yes)
			(layer "F.Fab")
			(hide yes)
			(effects
				(font
					(size 1.016 1.016)
					(thickness 0.1524)
				)
			)
		)
		(property "Device Type" "C805H58"
			(at -0.0762 -8.1534 180)
			(unlocked yes)
			(layer "F.Fab")
			(hide yes)
			(effects
				(font
					(size 1.016 1.016)
					(thickness 0.1524)
				)
			)
		)
		(duplicate_pad_numbers_are_jumpers no)
		(fp_line
			(start 0.635 0)
			(end -0.635 0)
			(stroke
				(width 0.508)
				(type default)
			)
			(layer "F.SilkS")
		)
		(fp_rect
			(start -0.9652 1.778)
			(end 0.9652 -1.778)
			(stroke
				(width 0)
				(type default)
			)
			(fill no)
			(layer "F.CrtYd")
		)
		(fp_poly
			(pts
				(xy -0.9652 -1.778) (xy 0.9652 -1.778) (xy 0.9652 1.778) (xy -0.9652 1.778)
			)
			(stroke
				(width 0)
				(type default)
			)
			(fill no)
			(layer "F.Fab")
		)
		(pad "1" smd rect
			(at 0 -0.9652 180)
			(size 1.397 1.143)
			(layers "F.Cu" "F.Mask" "F.Paste")
			(net "P5VC_12VIN")
		)
		(pad "2" smd rect
			(at 0 0.9652 180)
			(size 1.397 1.143)
			(layers "F.Cu" "F.Mask" "F.Paste")
			(net "GND")
		)
	)
	(footprint ""
		(layer "F.Cu")
		(at 5.079746 -494.8047 -90)
		(property "Reference" "PR43"
			(at 0 0 270)
			(layer "F.SilkS")
			(hide yes)
			(effects
				(font
					(size 1.27 1.27)
				)
			)
		)
		(property "Value" "10KR2D-GP"
			(at 0.064008 -3.993896 270)
			(unlocked yes)
			(layer "F.Fab")
			(hide yes)
			(effects
				(font
					(size 1.016 1.016)
					(thickness 0.1524)
				)
			)
		)
		(property "Device Type" "R402H16"
			(at 0.064008 -5.517896 270)
			(unlocked yes)
			(layer "F.Fab")
			(hide yes)
			(effects
				(font
					(size 1.016 1.016)
					(thickness 0.1524)
				)
			)
		)
		(duplicate_pad_numbers_are_jumpers no)
		(fp_line
			(start -0.508 -0.9398)
			(end -0.508 0.9398)
			(stroke
				(width 0.1524)
				(type default)
			)
			(layer "F.SilkS")
		)
		(fp_line
			(start 0.508 -0.9398)
			(end -0.508 -0.9398)
			(stroke
				(width 0.1524)
				(type default)
			)
			(layer "F.SilkS")
		)
		(fp_rect
			(start -0.508 0.9398)
			(end 0.508 -0.9398)
			(stroke
				(width 0)
				(type default)
			)
			(fill no)
			(layer "F.CrtYd")
		)
		(fp_rect
			(start -0.508 0.9398)
			(end 0.508 -0.9398)
			(stroke
				(width 0)
				(type default)
			)
			(fill no)
			(layer "F.Fab")
		)
		(pad "1" smd custom
			(at 0 -0.4445 270)
			(size 0.1397 0.1397)
			(layers "F.Cu" "F.Mask" "F.Paste")
			(net "P5VC_VFB")
			(options
				(clearance outline)
				(anchor circle)
			)
			(primitives
				(gr_poly
					(pts
						(arc
							(start -0.1778 -0.2794)
							(mid -0.249642 -0.249642)
							(end -0.2794 -0.1778)
						)
						(arc
							(start -0.2794 0.1778)
							(mid -0.249642 0.249642)
							(end -0.1778 0.2794)
						)
						(arc
							(start 0.1778 0.2794)
							(mid 0.249642 0.249642)
							(end 0.2794 0.1778)
						)
						(arc
							(start 0.2794 -0.1778)
							(mid 0.249642 -0.249642)
							(end 0.1778 -0.2794)
						)
					)
					(width 0)
					(fill yes)
				)
			)
		)
		(pad "2" smd custom
			(at 0 0.4445 270)
			(size 0.1397 0.1397)
			(layers "F.Cu" "F.Mask" "F.Paste")
			(net "P5VC_AGND")
			(options
				(clearance outline)
				(anchor circle)
			)
			(primitives
				(gr_poly
					(pts
						(arc
							(start -0.1778 -0.2794)
							(mid -0.249642 -0.249642)
							(end -0.2794 -0.1778)
						)
						(arc
							(start -0.2794 0.1778)
							(mid -0.249642 0.249642)
							(end -0.1778 0.2794)
						)
						(arc
							(start 0.1778 0.2794)
							(mid 0.249642 0.249642)
							(end 0.2794 0.1778)
						)
						(arc
							(start 0.2794 -0.1778)
							(mid 0.249642 -0.249642)
							(end 0.1778 -0.2794)
						)
					)
					(width 0)
					(fill yes)
				)
			)
		)
	)
	(footprint ""
		(layer "F.Cu")
		(at 32.86506 -372.298214 -90)
		(property "Reference" "C200"
			(at 0 0 270)
			(layer "F.SilkS")
			(hide yes)
			(effects
				(font
					(size 1.27 1.27)
				)
			)
		)
		(property "Value" "SCD01U50V2KX-1GP"
			(at 1.1811 -2.7051 270)
			(unlocked yes)
			(layer "F.Fab")
			(hide yes)
			(effects
				(font
					(size 1.016 1.016)
					(thickness 0.1524)
				)
			)
		)
		(property "Device Type" "C402H22"
			(at 1.1811 -4.2291 270)
			(unlocked yes)
			(layer "F.Fab")
			(hide yes)
			(effects
				(font
					(size 1.016 1.016)
					(thickness 0.1524)
				)
			)
		)
		(duplicate_pad_numbers_are_jumpers no)
		(fp_rect
			(start -0.4318 0.9525)
			(end 0.4318 -0.9525)
			(stroke
				(width 0)
				(type default)
			)
			(fill no)
			(layer "F.CrtYd")
		)
		(fp_rect
			(start -0.4318 0.9525)
			(end 0.4318 -0.9525)
			(stroke
				(width 0)
				(type default)
			)
			(fill no)
			(layer "F.Fab")
		)
		(pad "1" smd custom
			(at 0 -0.4445 270)
			(size 0.1524 0.1524)
			(layers "F.Cu" "F.Mask" "F.Paste")
			(net "SAS2X28_DRIVE_RX_N_B6")
			(options
				(clearance outline)
				(anchor circle)
			)
			(primitives
				(gr_poly
					(pts
						(arc
							(start 0.3048 -0.2032)
							(mid 0.275042 -0.275042)
							(end 0.2032 -0.3048)
						)
						(arc
							(start -0.2032 -0.3048)
							(mid -0.275042 -0.275042)
							(end -0.3048 -0.2032)
						)
						(arc
							(start -0.3048 0.2032)
							(mid -0.275042 0.275042)
							(end -0.2032 0.3048)
						)
						(arc
							(start 0.2032 0.3048)
							(mid 0.275042 0.275042)
							(end 0.3048 0.2032)
						)
					)
					(width 0)
					(fill yes)
				)
			)
		)
		(pad "2" smd custom
			(at 0 0.4445 270)
			(size 0.1524 0.1524)
			(layers "F.Cu" "F.Mask" "F.Paste")
			(net "SAS2X28_B_HDD6_RX_-")
			(options
				(clearance outline)
				(anchor circle)
			)
			(primitives
				(gr_poly
					(pts
						(arc
							(start 0.3048 -0.2032)
							(mid 0.275042 -0.275042)
							(end 0.2032 -0.3048)
						)
						(arc
							(start -0.2032 -0.3048)
							(mid -0.275042 -0.275042)
							(end -0.3048 -0.2032)
						)
						(arc
							(start -0.3048 0.2032)
							(mid -0.275042 0.275042)
							(end -0.2032 0.3048)
						)
						(arc
							(start 0.2032 0.3048)
							(mid 0.275042 0.275042)
							(end 0.3048 0.2032)
						)
					)
					(width 0)
					(fill yes)
				)
			)
		)
	)
)
